(kicad_pcb
	(version 20260206)
	(generator "pcbnew")
	(generator_version "10.0")
	(general
		(thickness 1.6)
		(legacy_teardrops no)
	)
	(paper "A4")
	(title_block
		(title "12092022_DA0F0TFB6D0_F0T_FAN_BOARD_MP5048_D_brd_v02_OCP.brd")
		(comment 1 "Grand Teton / footprints 197-203 of 924")
	)
	(layers
		(0 "F.Cu" signal "TOP")
		(4 "In1.Cu" signal "GND")
		(6 "In2.Cu" signal "IN1")
		(8 "In3.Cu" signal "IN2")
		(10 "In4.Cu" signal "GND1")
		(2 "B.Cu" signal "BOTTOM")
		(9 "F.Adhes" user "F.Adhesive")
		(11 "B.Adhes" user "B.Adhesive")
		(13 "F.Paste" user "Package Geometry/Pastemask Top")
		(15 "B.Paste" user "Package Geometry/Pastemask Bottom")
		(5 "F.SilkS" user "Ref Des/Silkscreen Top")
		(7 "B.SilkS" user "Ref Des/Silkscreen Bottom")
		(1 "F.Mask" user "Board Geometry/Soldermask Top")
		(3 "B.Mask" user "Board Geometry/Soldermask Bottom")
		(17 "Dwgs.User" user "User.Drawings")
		(19 "Cmts.User" user "User.Comments")
		(21 "Eco1.User" user "User.Eco1")
		(23 "Eco2.User" user "User.Eco2")
		(25 "Edge.Cuts" user "Board Geometry/Outline")
		(27 "Margin" user)
		(31 "F.CrtYd" user "Package Geometry/Place Bound Top")
		(29 "B.CrtYd" user "Package Geometry/Place Bound Bottom")
		(35 "F.Fab" user "Ref Des/Assembly Top")
		(33 "B.Fab" user "Ref Des/Assembly Bottom")
	)
	(footprint ""
		(layer "F.Cu")
		(at 11.43 -223.52 180)
		(property "Reference" "PC48"
			(at 5.334 -5.99567 0)
			(unlocked yes)
			(layer "F.SilkS")
			(effects
				(font
					(size 0.7874 0.5842)
					(thickness 0.1524)
				)
				(justify left)
			)
		)
		(property "Value" ""
			(at 0 0 180)
			(layer "F.Fab")
			(effects
				(font
					(size 1.27 1.27)
				)
			)
		)
		(duplicate_pad_numbers_are_jumpers no)
		(fp_line
			(start 5.249926 5.249926)
			(end 5.249926 1.2446)
			(stroke
				(width 0.1524)
				(type default)
			)
			(layer "F.SilkS")
		)
		(fp_line
			(start 5.249926 -1.2446)
			(end 5.249926 -5.249926)
			(stroke
				(width 0.1524)
				(type default)
			)
			(layer "F.SilkS")
		)
		(fp_line
			(start 5.249926 -5.249926)
			(end -3.979926 -5.249926)
			(stroke
				(width 0.1524)
				(type default)
			)
			(layer "F.SilkS")
		)
		(fp_line
			(start -3.979926 5.249926)
			(end 5.249926 5.249926)
			(stroke
				(width 0.1524)
				(type default)
			)
			(layer "F.SilkS")
		)
		(fp_line
			(start -3.979926 -5.249926)
			(end -5.249926 -3.979926)
			(stroke
				(width 0.1524)
				(type default)
			)
			(layer "F.SilkS")
		)
		(fp_line
			(start -5.249926 3.979926)
			(end -3.979926 5.249926)
			(stroke
				(width 0.1524)
				(type default)
			)
			(layer "F.SilkS")
		)
		(fp_line
			(start -5.249926 1.2446)
			(end -5.249926 3.979926)
			(stroke
				(width 0.1524)
				(type default)
			)
			(layer "F.SilkS")
		)
		(fp_line
			(start -5.249926 -3.979926)
			(end -5.249926 -1.2446)
			(stroke
				(width 0.1524)
				(type default)
			)
			(layer "F.SilkS")
		)
		(fp_line
			(start 5.249926 5.249926)
			(end 5.249926 -5.249926)
			(stroke
				(width 0.1)
				(type default)
			)
			(layer "F.Fab")
		)
		(fp_line
			(start 5.249926 -5.249926)
			(end -5.249926 -5.249926)
			(stroke
				(width 0.1)
				(type default)
			)
			(layer "F.Fab")
		)
		(fp_line
			(start -5.249926 5.249926)
			(end 5.249926 5.249926)
			(stroke
				(width 0.1)
				(type default)
			)
			(layer "F.Fab")
		)
		(fp_line
			(start -5.249926 -5.249926)
			(end -5.249926 5.249926)
			(stroke
				(width 0.1)
				(type default)
			)
			(layer "F.Fab")
		)
		(pad "1" smd rect
			(at -4.45008 0 270)
			(size 2.2098 4.4196)
			(layers "F.Cu" "F.Mask" "F.Paste")
			(net "P52V_FAN_6")
		)
		(pad "2" smd rect
			(at 4.45008 0 270)
			(size 2.2098 4.4196)
			(layers "F.Cu" "F.Mask" "F.Paste")
			(net "GND")
		)
	)
	(footprint ""
		(layer "F.Cu")
		(at 5.280914 -66.732912 180)
		(property "Reference" "R5353"
			(at 0 0 180)
			(layer "F.SilkS")
			(hide yes)
			(effects
				(font
					(size 1.27 1.27)
				)
			)
		)
		(property "Value" ""
			(at 0 0 180)
			(layer "F.Fab")
			(effects
				(font
					(size 1.27 1.27)
				)
			)
		)
		(duplicate_pad_numbers_are_jumpers no)
		(fp_line
			(start 0.7874 0.4064)
			(end -0.7874 0.4064)
			(stroke
				(width 0.1524)
				(type default)
			)
			(layer "F.SilkS")
		)
		(fp_line
			(start 0.7874 -0.4064)
			(end 0.7874 0.4064)
			(stroke
				(width 0.1524)
				(type default)
			)
			(layer "F.SilkS")
		)
		(fp_line
			(start -0.7874 0.4064)
			(end -0.7874 -0.4064)
			(stroke
				(width 0.1524)
				(type default)
			)
			(layer "F.SilkS")
		)
		(fp_line
			(start -0.7874 -0.4064)
			(end 0.7874 -0.4064)
			(stroke
				(width 0.1524)
				(type default)
			)
			(layer "F.SilkS")
		)
		(fp_line
			(start 0.67945 0.3048)
			(end 0.120396 0.3048)
			(stroke
				(width 0.1)
				(type default)
			)
			(layer "F.Fab")
		)
		(fp_line
			(start 0.67945 -0.3048)
			(end 0.67945 0.3048)
			(stroke
				(width 0.1)
				(type default)
			)
			(layer "F.Fab")
		)
		(fp_line
			(start 0.12065 -0.2794)
			(end 0.12065 -0.3048)
			(stroke
				(width 0.1)
				(type default)
			)
			(layer "F.Fab")
		)
		(fp_line
			(start 0.12065 -0.3048)
			(end 0.67945 -0.3048)
			(stroke
				(width 0.1)
				(type default)
			)
			(layer "F.Fab")
		)
		(fp_line
			(start 0.120396 0.3048)
			(end 0.120396 0.2794)
			(stroke
				(width 0.1)
				(type default)
			)
			(layer "F.Fab")
		)
		(fp_line
			(start 0.120396 0.2794)
			(end -0.12065 0.2794)
			(stroke
				(width 0.1)
				(type default)
			)
			(layer "F.Fab")
		)
		(fp_line
			(start -0.12065 0.3048)
			(end -0.67945 0.3048)
			(stroke
				(width 0.1)
				(type default)
			)
			(layer "F.Fab")
		)
		(fp_line
			(start -0.12065 0.2794)
			(end -0.12065 0.3048)
			(stroke
				(width 0.1)
				(type default)
			)
			(layer "F.Fab")
		)
		(fp_line
			(start -0.12065 -0.2794)
			(end 0.12065 -0.2794)
			(stroke
				(width 0.1)
				(type default)
			)
			(layer "F.Fab")
		)
		(fp_line
			(start -0.12065 -0.305054)
			(end -0.12065 -0.2794)
			(stroke
				(width 0.1)
				(type default)
			)
			(layer "F.Fab")
		)
		(fp_line
			(start -0.67945 0.3048)
			(end -0.67945 -0.305054)
			(stroke
				(width 0.1)
				(type default)
			)
			(layer "F.Fab")
		)
		(fp_line
			(start -0.67945 -0.305054)
			(end -0.12065 -0.305054)
			(stroke
				(width 0.1)
				(type default)
			)
			(layer "F.Fab")
		)
		(pad "1" smd circle
			(at -0.40005 0 180)
			(size 0 0)
			(layers "F.Cu" "F.Mask" "F.Paste")
			(net "FAN_4_PRESENT_R")
		)
		(pad "2" smd circle
			(at 0.40005 0 180)
			(size 0 0)
			(layers "F.Cu" "F.Mask" "F.Paste")
			(net "FAN_4_PRESENT")
		)
	)
	(footprint ""
		(layer "F.Cu")
		(at 10.850118 -157.661102)
		(property "Reference" "H3"
			(at -0.563118 17.225772 0)
			(unlocked yes)
			(layer "F.SilkS")
			(effects
				(font
					(size 0.7874 0.5842)
					(thickness 0.1524)
				)
				(justify left)
			)
		)
		(property "Value" ""
			(at 0 0 0)
			(layer "F.Fab")
			(effects
				(font
					(size 1.27 1.27)
				)
			)
		)
		(duplicate_pad_numbers_are_jumpers no)
		(pad "1" thru_hole oval
			(at 0 0)
			(size 9.017 21.0058)
			(drill 3.0226
				(offset 0 5.999988)
			)
			(layers "*.Cu" "*.Mask")
			(remove_unused_layers no)
			(net "GND")
			(clearance -1.500378)
			(padstack
				(mode front_inner_back)
				(layer "Inner"
					(shape circle)
					(size 0 0)
					(clearance 0)
				)
				(layer "B.Cu"
					(shape oval)
					(size 9.017 21.0058)
					(offset 0 5.999988)
					(clearance -1.500378)
				)
			)
		)
	)
	(footprint ""
		(layer "F.Cu")
		(at 48.26 -130.937 180)
		(property "Reference" "R5559"
			(at 0 0 180)
			(layer "F.SilkS")
			(hide yes)
			(effects
				(font
					(size 1.27 1.27)
				)
			)
		)
		(property "Value" ""
			(at 0 0 180)
			(layer "F.Fab")
			(effects
				(font
					(size 1.27 1.27)
				)
			)
		)
		(duplicate_pad_numbers_are_jumpers no)
		(fp_line
			(start 0.7874 0.4064)
			(end -0.7874 0.4064)
			(stroke
				(width 0.1524)
				(type default)
			)
			(layer "F.SilkS")
		)
		(fp_line
			(start 0.7874 -0.4064)
			(end 0.7874 0.4064)
			(stroke
				(width 0.1524)
				(type default)
			)
			(layer "F.SilkS")
		)
		(fp_line
			(start -0.7874 0.4064)
			(end -0.7874 -0.4064)
			(stroke
				(width 0.1524)
				(type default)
			)
			(layer "F.SilkS")
		)
		(fp_line
			(start -0.7874 -0.4064)
			(end 0.7874 -0.4064)
			(stroke
				(width 0.1524)
				(type default)
			)
			(layer "F.SilkS")
		)
		(fp_line
			(start 0.67945 0.3048)
			(end 0.120396 0.3048)
			(stroke
				(width 0.1)
				(type default)
			)
			(layer "F.Fab")
		)
		(fp_line
			(start 0.67945 -0.3048)
			(end 0.67945 0.3048)
			(stroke
				(width 0.1)
				(type default)
			)
			(layer "F.Fab")
		)
		(fp_line
			(start 0.12065 -0.2794)
			(end 0.12065 -0.3048)
			(stroke
				(width 0.1)
				(type default)
			)
			(layer "F.Fab")
		)
		(fp_line
			(start 0.12065 -0.3048)
			(end 0.67945 -0.3048)
			(stroke
				(width 0.1)
				(type default)
			)
			(layer "F.Fab")
		)
		(fp_line
			(start 0.120396 0.3048)
			(end 0.120396 0.2794)
			(stroke
				(width 0.1)
				(type default)
			)
			(layer "F.Fab")
		)
		(fp_line
			(start 0.120396 0.2794)
			(end -0.12065 0.2794)
			(stroke
				(width 0.1)
				(type default)
			)
			(layer "F.Fab")
		)
		(fp_line
			(start -0.12065 0.3048)
			(end -0.67945 0.3048)
			(stroke
				(width 0.1)
				(type default)
			)
			(layer "F.Fab")
		)
		(fp_line
			(start -0.12065 0.2794)
			(end -0.12065 0.3048)
			(stroke
				(width 0.1)
				(type default)
			)
			(layer "F.Fab")
		)
		(fp_line
			(start -0.12065 -0.2794)
			(end 0.12065 -0.2794)
			(stroke
				(width 0.1)
				(type default)
			)
			(layer "F.Fab")
		)
		(fp_line
			(start -0.12065 -0.305054)
			(end -0.12065 -0.2794)
			(stroke
				(width 0.1)
				(type default)
			)
			(layer "F.Fab")
		)
		(fp_line
			(start -0.67945 0.3048)
			(end -0.67945 -0.305054)
			(stroke
				(width 0.1)
				(type default)
			)
			(layer "F.Fab")
		)
		(fp_line
			(start -0.67945 -0.305054)
			(end -0.12065 -0.305054)
			(stroke
				(width 0.1)
				(type default)
			)
			(layer "F.Fab")
		)
		(pad "1" smd circle
			(at -0.40005 0 180)
			(size 0 0)
			(layers "F.Cu" "F.Mask" "F.Paste")
			(net "P3V3_AUX")
		)
		(pad "2" smd circle
			(at 0.40005 0 180)
			(size 0 0)
			(layers "F.Cu" "F.Mask" "F.Paste")
			(net "U403_ADD0")
		)
	)
	(footprint ""
		(layer "F.Cu")
		(at 29.464 -19.05 -90)
		(property "Reference" "U399"
			(at 1.3462 -1.77927 90)
			(unlocked yes)
			(layer "F.SilkS")
			(effects
				(font
					(size 0.7874 0.5842)
					(thickness 0.1524)
				)
				(justify left)
			)
		)
		(property "Value" ""
			(at 0 0 270)
			(layer "F.Fab")
			(effects
				(font
					(size 1.27 1.27)
				)
			)
		)
		(duplicate_pad_numbers_are_jumpers no)
		(fp_line
			(start -1.33096 1.100074)
			(end -1.33096 -1.100074)
			(stroke
				(width 0.1524)
				(type default)
			)
			(layer "F.SilkS")
		)
		(fp_line
			(start 1.33096 1.100074)
			(end -1.33096 1.100074)
			(stroke
				(width 0.1524)
				(type default)
			)
			(layer "F.SilkS")
		)
		(fp_line
			(start 0 -0.649986)
			(end 0.381 -1.100074)
			(stroke
				(width 0.1524)
				(type default)
			)
			(layer "F.SilkS")
		)
		(fp_line
			(start -1.33096 -1.100074)
			(end -0.381 -1.100074)
			(stroke
				(width 0.1524)
				(type default)
			)
			(layer "F.SilkS")
		)
		(fp_line
			(start -0.381 -1.100074)
			(end 0 -0.649986)
			(stroke
				(width 0.1524)
				(type default)
			)
			(layer "F.SilkS")
		)
		(fp_line
			(start 0.381 -1.100074)
			(end 1.33096 -1.100074)
			(stroke
				(width 0.1524)
				(type default)
			)
			(layer "F.SilkS")
		)
		(fp_line
			(start 1.33096 -1.100074)
			(end 1.33096 1.100074)
			(stroke
				(width 0.1524)
				(type default)
			)
			(layer "F.SilkS")
		)
		(fp_poly
			(pts
				(xy -1.92659 -1.45669) (xy -2.285746 -1.097534) (xy -1.56718 -0.738124)
			)
			(stroke
				(width 0)
				(type default)
			)
			(fill yes)
			(layer "F.SilkS")
		)
		(fp_line
			(start -0.674878 1.100074)
			(end -0.674878 -1.100074)
			(stroke
				(width 0.1)
				(type default)
			)
			(layer "F.Fab")
		)
		(fp_line
			(start 0.674878 1.100074)
			(end -0.674878 1.100074)
			(stroke
				(width 0.1)
				(type default)
			)
			(layer "F.Fab")
		)
		(fp_line
			(start -0.674878 -1.100074)
			(end 0.674878 -1.100074)
			(stroke
				(width 0.1)
				(type default)
			)
			(layer "F.Fab")
		)
		(fp_line
			(start 0.674878 -1.100074)
			(end 0.674878 1.100074)
			(stroke
				(width 0.1)
				(type default)
			)
			(layer "F.Fab")
		)
		(fp_poly
			(pts
				(xy -2.209292 -0.902462) (xy -2.209292 -0.394462) (xy -1.447292 -0.648462)
			)
			(stroke
				(width 0)
				(type default)
			)
			(fill yes)
			(layer "F.Fab")
		)
		(pad "1" smd rect
			(at -0.94996 -0.649986)
			(size 0.4064 0.508)
			(layers "F.Cu" "F.Mask" "F.Paste")
			(net "NC_U399_P1")
		)
		(pad "2" smd rect
			(at -0.94996 0)
			(size 0.4064 0.508)
			(layers "F.Cu" "F.Mask" "F.Paste")
			(net "FAN_4_PWM")
		)
		(pad "3" smd rect
			(at -0.94996 0.649986)
			(size 0.4064 0.508)
			(layers "F.Cu" "F.Mask" "F.Paste")
			(net "GND")
		)
		(pad "4" smd rect
			(at 0.94996 0.649986)
			(size 0.4064 0.508)
			(layers "F.Cu" "F.Mask" "F.Paste")
			(net "FAN_4_PWM_BUF")
		)
		(pad "5" smd rect
			(at 0.94996 -0.649986)
			(size 0.4064 0.508)
			(layers "F.Cu" "F.Mask" "F.Paste")
			(net "P3V3_AUX")
		)
	)
	(footprint ""
		(layer "F.Cu")
		(at 36.703 -63.246)
		(property "Reference" "PR43"
			(at 0 0 0)
			(layer "F.SilkS")
			(hide yes)
			(effects
				(font
					(size 1.27 1.27)
				)
			)
		)
		(property "Value" ""
			(at 0 0 0)
			(layer "F.Fab")
			(effects
				(font
					(size 1.27 1.27)
				)
			)
		)
		(duplicate_pad_numbers_are_jumpers no)
		(fp_line
			(start -0.7874 -0.4064)
			(end 0.7874 -0.4064)
			(stroke
				(width 0.1524)
				(type default)
			)
			(layer "F.SilkS")
		)
		(fp_line
			(start -0.7874 0.4064)
			(end -0.7874 -0.4064)
			(stroke
				(width 0.1524)
				(type default)
			)
			(layer "F.SilkS")
		)
		(fp_line
			(start 0.7874 -0.4064)
			(end 0.7874 0.4064)
			(stroke
				(width 0.1524)
				(type default)
			)
			(layer "F.SilkS")
		)
		(fp_line
			(start 0.7874 0.4064)
			(end -0.7874 0.4064)
			(stroke
				(width 0.1524)
				(type default)
			)
			(layer "F.SilkS")
		)
		(fp_line
			(start -0.67945 -0.305054)
			(end -0.12065 -0.305054)
			(stroke
				(width 0.1)
				(type default)
			)
			(layer "F.Fab")
		)
		(fp_line
			(start -0.67945 0.3048)
			(end -0.67945 -0.305054)
			(stroke
				(width 0.1)
				(type default)
			)
			(layer "F.Fab")
		)
		(fp_line
			(start -0.12065 -0.305054)
			(end -0.12065 -0.2794)
			(stroke
				(width 0.1)
				(type default)
			)
			(layer "F.Fab")
		)
		(fp_line
			(start -0.12065 -0.2794)
			(end 0.12065 -0.2794)
			(stroke
				(width 0.1)
				(type default)
			)
			(layer "F.Fab")
		)
		(fp_line
			(start -0.12065 0.2794)
			(end -0.12065 0.3048)
			(stroke
				(width 0.1)
				(type default)
			)
			(layer "F.Fab")
		)
		(fp_line
			(start -0.12065 0.3048)
			(end -0.67945 0.3048)
			(stroke
				(width 0.1)
				(type default)
			)
			(layer "F.Fab")
		)
		(fp_line
			(start 0.120396 0.2794)
			(end -0.12065 0.2794)
			(stroke
				(width 0.1)
				(type default)
			)
			(layer "F.Fab")
		)
		(fp_line
			(start 0.120396 0.3048)
			(end 0.120396 0.2794)
			(stroke
				(width 0.1)
				(type default)
			)
			(layer "F.Fab")
		)
		(fp_line
			(start 0.12065 -0.3048)
			(end 0.67945 -0.3048)
			(stroke
				(width 0.1)
				(type default)
			)
			(layer "F.Fab")
		)
		(fp_line
			(start 0.12065 -0.2794)
			(end 0.12065 -0.3048)
			(stroke
				(width 0.1)
				(type default)
			)
			(layer "F.Fab")
		)
		(fp_line
			(start 0.67945 -0.3048)
			(end 0.67945 0.3048)
			(stroke
				(width 0.1)
				(type default)
			)
			(layer "F.Fab")
		)
		(fp_line
			(start 0.67945 0.3048)
			(end 0.120396 0.3048)
			(stroke
				(width 0.1)
				(type default)
			)
			(layer "F.Fab")
		)
		(pad "1" smd circle
			(at -0.40005 0)
			(size 0 0)
			(layers "F.Cu" "F.Mask" "F.Paste")
			(net "FAN_3_MODE")
		)
		(pad "2" smd circle
			(at 0.40005 0)
			(size 0 0)
			(layers "F.Cu" "F.Mask" "F.Paste")
			(net "GND")
		)
	)
	(footprint ""
		(layer "F.Cu")
		(at 32.258 -18.542 90)
		(property "Reference" "R5395"
			(at 0 0 90)
			(layer "F.SilkS")
			(hide yes)
			(effects
				(font
					(size 1.27 1.27)
				)
			)
		)
		(property "Value" ""
			(at 0 0 90)
			(layer "F.Fab")
			(effects
				(font
					(size 1.27 1.27)
				)
			)
		)
		(duplicate_pad_numbers_are_jumpers no)
		(fp_line
			(start 0.7874 -0.4064)
			(end 0.7874 0.4064)
			(stroke
				(width 0.1524)
				(type default)
			)
			(layer "F.SilkS")
		)
		(fp_line
			(start -0.7874 -0.4064)
			(end 0.7874 -0.4064)
			(stroke
				(width 0.1524)
				(type default)
			)
			(layer "F.SilkS")
		)
		(fp_line
			(start 0.7874 0.4064)
			(end -0.7874 0.4064)
			(stroke
				(width 0.1524)
				(type default)
			)
			(layer "F.SilkS")
		)
		(fp_line
			(start -0.7874 0.4064)
			(end -0.7874 -0.4064)
			(stroke
				(width 0.1524)
				(type default)
			)
			(layer "F.SilkS")
		)
		(fp_line
			(start -0.12065 -0.305054)
			(end -0.12065 -0.2794)
			(stroke
				(width 0.1)
				(type default)
			)
			(layer "F.Fab")
		)
		(fp_line
			(start -0.67945 -0.305054)
			(end -0.12065 -0.305054)
			(stroke
				(width 0.1)
				(type default)
			)
			(layer "F.Fab")
		)
		(fp_line
			(start 0.67945 -0.3048)
			(end 0.67945 0.3048)
			(stroke
				(width 0.1)
				(type default)
			)
			(layer "F.Fab")
		)
		(fp_line
			(start 0.12065 -0.3048)
			(end 0.67945 -0.3048)
			(stroke
				(width 0.1)
				(type default)
			)
			(layer "F.Fab")
		)
		(fp_line
			(start 0.12065 -0.2794)
			(end 0.12065 -0.3048)
			(stroke
				(width 0.1)
				(type default)
			)
			(layer "F.Fab")
		)
		(fp_line
			(start -0.12065 -0.2794)
			(end 0.12065 -0.2794)
			(stroke
				(width 0.1)
				(type default)
			)
			(layer "F.Fab")
		)
		(fp_line
			(start 0.120396 0.2794)
			(end -0.12065 0.2794)
			(stroke
				(width 0.1)
				(type default)
			)
			(layer "F.Fab")
		)
		(fp_line
			(start -0.12065 0.2794)
			(end -0.12065 0.3048)
			(stroke
				(width 0.1)
				(type default)
			)
			(layer "F.Fab")
		)
		(fp_line
			(start 0.67945 0.3048)
			(end 0.120396 0.3048)
			(stroke
				(width 0.1)
				(type default)
			)
			(layer "F.Fab")
		)
		(fp_line
			(start 0.120396 0.3048)
			(end 0.120396 0.2794)
			(stroke
				(width 0.1)
				(type default)
			)
			(layer "F.Fab")
		)
		(fp_line
			(start -0.12065 0.3048)
			(end -0.67945 0.3048)
			(stroke
				(width 0.1)
				(type default)
			)
			(layer "F.Fab")
		)
		(fp_line
			(start -0.67945 0.3048)
			(end -0.67945 -0.305054)
			(stroke
				(width 0.1)
				(type default)
			)
			(layer "F.Fab")
		)
		(pad "1" smd circle
			(at -0.40005 0 90)
			(size 0 0)
			(layers "F.Cu" "F.Mask" "F.Paste")
			(net "P3V3_AUX")
		)
		(pad "2" smd circle
			(at 0.40005 0 90)
			(size 0 0)
			(layers "F.Cu" "F.Mask" "F.Paste")
			(net "FAN_3_OK_R_LED")
		)
	)
)
